#ISCELL
  mstr_symbols design_note *
  *
#ISCELL
  mstr_symbols intel_corp_bpage *
  *
#ISCELL
  mstr_symbols vcc_core *
  page36_i12
#ISCELL
  mstr_symbols vcc_core *
  page36_i13
#ISCELL
  mstr_symbols vcc_core *
  page36_i14
#CELL
  chpset_lib skx_ext_b *
  page36_i15
#CELL
  chpset_lib skx_ext_b *
  page36_i16
#ISCELL
  mstr_standard offpage *
  page36_i5
#ISCELL
  mstr_standard offpage *
  page36_i8
